(kicad_pcb
	(version 20260206)
	(generator "pcbnew")
	(generator_version "10.0")
	(general
		(thickness 1.6)
		(legacy_teardrops no)
	)
	(paper "A4")
	(title_block
		(title "03242023_DA0F0TMBIJ0_F0T_Motherboard_J_brd_V01_OCP.brd")
		(comment 1 "Grand Teton / footprints 1762-1767 of 6105")
	)
	(layers
		(0 "F.Cu" signal "TOP")
		(4 "In1.Cu" signal "GND")
		(6 "In2.Cu" signal "IN1")
		(8 "In3.Cu" signal "GND1")
		(10 "In4.Cu" signal "IN2")
		(12 "In5.Cu" signal "GND2")
		(14 "In6.Cu" signal "IN3")
		(16 "In7.Cu" signal "GND3")
		(18 "In8.Cu" signal "VCC")
		(20 "In9.Cu" signal "VCC1")
		(22 "In10.Cu" signal "GND4")
		(24 "In11.Cu" signal "IN4")
		(26 "In12.Cu" signal "GND5")
		(28 "In13.Cu" signal "IN5")
		(30 "In14.Cu" signal "GND6")
		(32 "In15.Cu" signal "IN6")
		(34 "In16.Cu" signal "GND7")
		(2 "B.Cu" signal "BOTTOM")
		(9 "F.Adhes" user "F.Adhesive")
		(11 "B.Adhes" user "B.Adhesive")
		(13 "F.Paste" user "Package Geometry/Pastemask Top")
		(15 "B.Paste" user "Package Geometry/Pastemask Bottom")
		(5 "F.SilkS" user "Ref Des/Silkscreen Top")
		(7 "B.SilkS" user "Ref Des/Silkscreen Bottom")
		(1 "F.Mask" user "Board Geometry/Soldermask Top")
		(3 "B.Mask" user "Board Geometry/Soldermask Bottom")
		(17 "Dwgs.User" user "User.Drawings")
		(19 "Cmts.User" user "User.Comments")
		(21 "Eco1.User" user "User.Eco1")
		(23 "Eco2.User" user "User.Eco2")
		(25 "Edge.Cuts" user "Board Geometry/Outline")
		(27 "Margin" user)
		(31 "F.CrtYd" user "Package Geometry/Place Bound Top")
		(29 "B.CrtYd" user "Package Geometry/Place Bound Bottom")
		(35 "F.Fab" user "Ref Des/Assembly Top")
		(33 "B.Fab" user "Ref Des/Assembly Bottom")
	)
	(footprint ""
		(layer "F.Cu")
		(at 34.370518 -122.380502 -90)
		(property "Reference" "R2453"
			(at 0 0 270)
			(layer "F.SilkS")
			(hide yes)
			(effects
				(font
					(size 1.27 1.27)
				)
			)
		)
		(property "Value" ""
			(at 0 0 270)
			(layer "F.Fab")
			(effects
				(font
					(size 1.27 1.27)
				)
			)
		)
		(duplicate_pad_numbers_are_jumpers no)
		(fp_line
			(start -0.7874 0.4064)
			(end -0.7874 -0.4064)
			(stroke
				(width 0.1524)
				(type default)
			)
			(layer "F.SilkS")
		)
		(fp_line
			(start 0.7874 0.4064)
			(end -0.7874 0.4064)
			(stroke
				(width 0.1524)
				(type default)
			)
			(layer "F.SilkS")
		)
		(fp_line
			(start -0.7874 -0.4064)
			(end 0.7874 -0.4064)
			(stroke
				(width 0.1524)
				(type default)
			)
			(layer "F.SilkS")
		)
		(fp_line
			(start 0.7874 -0.4064)
			(end 0.7874 0.4064)
			(stroke
				(width 0.1524)
				(type default)
			)
			(layer "F.SilkS")
		)
		(fp_line
			(start -0.67945 0.3048)
			(end -0.67945 -0.305054)
			(stroke
				(width 0.1)
				(type default)
			)
			(layer "F.Fab")
		)
		(fp_line
			(start -0.12065 0.3048)
			(end -0.67945 0.3048)
			(stroke
				(width 0.1)
				(type default)
			)
			(layer "F.Fab")
		)
		(fp_line
			(start 0.120396 0.3048)
			(end 0.120396 0.2794)
			(stroke
				(width 0.1)
				(type default)
			)
			(layer "F.Fab")
		)
		(fp_line
			(start 0.67945 0.3048)
			(end 0.120396 0.3048)
			(stroke
				(width 0.1)
				(type default)
			)
			(layer "F.Fab")
		)
		(fp_line
			(start -0.12065 0.2794)
			(end -0.12065 0.3048)
			(stroke
				(width 0.1)
				(type default)
			)
			(layer "F.Fab")
		)
		(fp_line
			(start 0.120396 0.2794)
			(end -0.12065 0.2794)
			(stroke
				(width 0.1)
				(type default)
			)
			(layer "F.Fab")
		)
		(fp_line
			(start -0.12065 -0.2794)
			(end 0.12065 -0.2794)
			(stroke
				(width 0.1)
				(type default)
			)
			(layer "F.Fab")
		)
		(fp_line
			(start 0.12065 -0.2794)
			(end 0.12065 -0.3048)
			(stroke
				(width 0.1)
				(type default)
			)
			(layer "F.Fab")
		)
		(fp_line
			(start 0.12065 -0.3048)
			(end 0.67945 -0.3048)
			(stroke
				(width 0.1)
				(type default)
			)
			(layer "F.Fab")
		)
		(fp_line
			(start 0.67945 -0.3048)
			(end 0.67945 0.3048)
			(stroke
				(width 0.1)
				(type default)
			)
			(layer "F.Fab")
		)
		(fp_line
			(start -0.67945 -0.305054)
			(end -0.12065 -0.305054)
			(stroke
				(width 0.1)
				(type default)
			)
			(layer "F.Fab")
		)
		(fp_line
			(start -0.12065 -0.305054)
			(end -0.12065 -0.2794)
			(stroke
				(width 0.1)
				(type default)
			)
			(layer "F.Fab")
		)
		(pad "1" smd circle
			(at -0.40005 0 270)
			(size 0 0)
			(layers "F.Cu" "F.Mask" "F.Paste")
			(net "SMB_VR_3V3AUX_SCL_R")
		)
		(pad "2" smd circle
			(at 0.40005 0 270)
			(size 0 0)
			(layers "F.Cu" "F.Mask" "F.Paste")
			(net "SMB_VR_3V3AUX_SCL_R2")
		)
	)
	(footprint ""
		(layer "F.Cu")
		(at 21.44522 -335.905094 -90)
		(property "Reference" "R1837"
			(at 0 0 270)
			(layer "F.SilkS")
			(hide yes)
			(effects
				(font
					(size 1.27 1.27)
				)
			)
		)
		(property "Value" ""
			(at 0 0 270)
			(layer "F.Fab")
			(effects
				(font
					(size 1.27 1.27)
				)
			)
		)
		(duplicate_pad_numbers_are_jumpers no)
		(fp_line
			(start -4.0386 1.7526)
			(end -4.0386 -1.7526)
			(stroke
				(width 0.1524)
				(type default)
			)
			(layer "F.SilkS")
		)
		(fp_line
			(start 4.0386 1.7526)
			(end -4.0386 1.7526)
			(stroke
				(width 0.1524)
				(type default)
			)
			(layer "F.SilkS")
		)
		(fp_line
			(start -4.0386 -1.7526)
			(end 4.0386 -1.7526)
			(stroke
				(width 0.1524)
				(type default)
			)
			(layer "F.SilkS")
		)
		(fp_line
			(start 4.0386 -1.7526)
			(end 4.0386 1.7526)
			(stroke
				(width 0.1524)
				(type default)
			)
			(layer "F.SilkS")
		)
		(fp_line
			(start -4.0386 1.7526)
			(end -4.0386 -1.7526)
			(stroke
				(width 0.1)
				(type default)
			)
			(layer "F.Fab")
		)
		(fp_line
			(start 4.0386 1.7526)
			(end -4.0386 1.7526)
			(stroke
				(width 0.1)
				(type default)
			)
			(layer "F.Fab")
		)
		(fp_line
			(start -4.0386 -1.7526)
			(end 4.0386 -1.7526)
			(stroke
				(width 0.1)
				(type default)
			)
			(layer "F.Fab")
		)
		(fp_line
			(start 4.0386 -1.7526)
			(end 4.0386 1.7526)
			(stroke
				(width 0.1)
				(type default)
			)
			(layer "F.Fab")
		)
		(pad "1" smd circle
			(at -3.700018 0 180)
			(size 0 0)
			(layers "F.Cu" "F.Mask" "F.Paste")
			(net "P12V_AUX")
		)
		(pad "2" smd circle
			(at 3.700018 0)
			(size 0 0)
			(layers "F.Cu" "F.Mask" "F.Paste")
			(net "P12V_S3_AUX_CPU1_NVDIMM")
		)
		(pad "3" smd rect
			(at -2.70002 0)
			(size 0.4064 1.1176)
			(layers "F.Cu" "F.Mask" "F.Paste")
			(net "P12V_AUX_CPU1_DIMM_ISEN_P")
		)
		(pad "4" smd rect
			(at 2.70002 0)
			(size 0.4064 1.1176)
			(layers "F.Cu" "F.Mask" "F.Paste")
			(net "P12V_AUX_CPU1_DIMM_ISEN_N")
		)
	)
	(footprint ""
		(layer "F.Cu")
		(at 420.591488 -182.290974 180)
		(property "Reference" "PC1346"
			(at 0 0 180)
			(layer "F.SilkS")
			(hide yes)
			(effects
				(font
					(size 1.27 1.27)
				)
			)
		)
		(property "Value" ""
			(at 0 0 180)
			(layer "F.Fab")
			(effects
				(font
					(size 1.27 1.27)
				)
			)
		)
		(duplicate_pad_numbers_are_jumpers no)
		(fp_line
			(start 0.7874 0.4064)
			(end -0.7874 0.4064)
			(stroke
				(width 0.1524)
				(type default)
			)
			(layer "F.SilkS")
		)
		(fp_line
			(start 0.7874 -0.4064)
			(end 0.7874 0.4064)
			(stroke
				(width 0.1524)
				(type default)
			)
			(layer "F.SilkS")
		)
		(fp_line
			(start -0.7874 0.4064)
			(end -0.7874 -0.4064)
			(stroke
				(width 0.1524)
				(type default)
			)
			(layer "F.SilkS")
		)
		(fp_line
			(start -0.7874 -0.4064)
			(end 0.7874 -0.4064)
			(stroke
				(width 0.1524)
				(type default)
			)
			(layer "F.SilkS")
		)
		(fp_line
			(start 0.67945 0.3048)
			(end 0.120396 0.3048)
			(stroke
				(width 0.1)
				(type default)
			)
			(layer "F.Fab")
		)
		(fp_line
			(start 0.67945 -0.3048)
			(end 0.67945 0.3048)
			(stroke
				(width 0.1)
				(type default)
			)
			(layer "F.Fab")
		)
		(fp_line
			(start 0.12065 -0.2794)
			(end 0.12065 -0.3048)
			(stroke
				(width 0.1)
				(type default)
			)
			(layer "F.Fab")
		)
		(fp_line
			(start 0.12065 -0.3048)
			(end 0.67945 -0.3048)
			(stroke
				(width 0.1)
				(type default)
			)
			(layer "F.Fab")
		)
		(fp_line
			(start 0.120396 0.3048)
			(end 0.120396 0.2794)
			(stroke
				(width 0.1)
				(type default)
			)
			(layer "F.Fab")
		)
		(fp_line
			(start 0.120396 0.2794)
			(end -0.12065 0.2794)
			(stroke
				(width 0.1)
				(type default)
			)
			(layer "F.Fab")
		)
		(fp_line
			(start -0.12065 0.3048)
			(end -0.67945 0.3048)
			(stroke
				(width 0.1)
				(type default)
			)
			(layer "F.Fab")
		)
		(fp_line
			(start -0.12065 0.2794)
			(end -0.12065 0.3048)
			(stroke
				(width 0.1)
				(type default)
			)
			(layer "F.Fab")
		)
		(fp_line
			(start -0.12065 -0.2794)
			(end 0.12065 -0.2794)
			(stroke
				(width 0.1)
				(type default)
			)
			(layer "F.Fab")
		)
		(fp_line
			(start -0.12065 -0.305054)
			(end -0.12065 -0.2794)
			(stroke
				(width 0.1)
				(type default)
			)
			(layer "F.Fab")
		)
		(fp_line
			(start -0.67945 0.3048)
			(end -0.67945 -0.305054)
			(stroke
				(width 0.1)
				(type default)
			)
			(layer "F.Fab")
		)
		(fp_line
			(start -0.67945 -0.305054)
			(end -0.12065 -0.305054)
			(stroke
				(width 0.1)
				(type default)
			)
			(layer "F.Fab")
		)
		(pad "1" smd circle
			(at -0.40005 0 180)
			(size 0 0)
			(layers "F.Cu" "F.Mask" "F.Paste")
			(net "GND")
		)
		(pad "2" smd circle
			(at 0.40005 0 180)
			(size 0 0)
			(layers "F.Cu" "F.Mask" "F.Paste")
			(net "PVCCINFAON_CPU0_VREF")
		)
	)
	(footprint ""
		(layer "F.Cu")
		(at 36.930584 -108.555282)
		(property "Reference" "C2048"
			(at 0 0 0)
			(layer "F.SilkS")
			(hide yes)
			(effects
				(font
					(size 1.27 1.27)
				)
			)
		)
		(property "Value" ""
			(at 0 0 0)
			(layer "F.Fab")
			(effects
				(font
					(size 1.27 1.27)
				)
			)
		)
		(duplicate_pad_numbers_are_jumpers no)
		(fp_line
			(start -0.7874 -0.4064)
			(end 0.7874 -0.4064)
			(stroke
				(width 0.1524)
				(type default)
			)
			(layer "F.SilkS")
		)
		(fp_line
			(start -0.7874 0.4064)
			(end -0.7874 -0.4064)
			(stroke
				(width 0.1524)
				(type default)
			)
			(layer "F.SilkS")
		)
		(fp_line
			(start 0.7874 -0.4064)
			(end 0.7874 0.4064)
			(stroke
				(width 0.1524)
				(type default)
			)
			(layer "F.SilkS")
		)
		(fp_line
			(start 0.7874 0.4064)
			(end -0.7874 0.4064)
			(stroke
				(width 0.1524)
				(type default)
			)
			(layer "F.SilkS")
		)
		(fp_line
			(start -0.67945 -0.305054)
			(end -0.12065 -0.305054)
			(stroke
				(width 0.1)
				(type default)
			)
			(layer "F.Fab")
		)
		(fp_line
			(start -0.67945 0.3048)
			(end -0.67945 -0.305054)
			(stroke
				(width 0.1)
				(type default)
			)
			(layer "F.Fab")
		)
		(fp_line
			(start -0.12065 -0.305054)
			(end -0.12065 -0.2794)
			(stroke
				(width 0.1)
				(type default)
			)
			(layer "F.Fab")
		)
		(fp_line
			(start -0.12065 -0.2794)
			(end 0.12065 -0.2794)
			(stroke
				(width 0.1)
				(type default)
			)
			(layer "F.Fab")
		)
		(fp_line
			(start -0.12065 0.2794)
			(end -0.12065 0.3048)
			(stroke
				(width 0.1)
				(type default)
			)
			(layer "F.Fab")
		)
		(fp_line
			(start -0.12065 0.3048)
			(end -0.67945 0.3048)
			(stroke
				(width 0.1)
				(type default)
			)
			(layer "F.Fab")
		)
		(fp_line
			(start 0.120396 0.2794)
			(end -0.12065 0.2794)
			(stroke
				(width 0.1)
				(type default)
			)
			(layer "F.Fab")
		)
		(fp_line
			(start 0.120396 0.3048)
			(end 0.120396 0.2794)
			(stroke
				(width 0.1)
				(type default)
			)
			(layer "F.Fab")
		)
		(fp_line
			(start 0.12065 -0.3048)
			(end 0.67945 -0.3048)
			(stroke
				(width 0.1)
				(type default)
			)
			(layer "F.Fab")
		)
		(fp_line
			(start 0.12065 -0.2794)
			(end 0.12065 -0.3048)
			(stroke
				(width 0.1)
				(type default)
			)
			(layer "F.Fab")
		)
		(fp_line
			(start 0.67945 -0.3048)
			(end 0.67945 0.3048)
			(stroke
				(width 0.1)
				(type default)
			)
			(layer "F.Fab")
		)
		(fp_line
			(start 0.67945 0.3048)
			(end 0.120396 0.3048)
			(stroke
				(width 0.1)
				(type default)
			)
			(layer "F.Fab")
		)
		(pad "1" smd circle
			(at -0.40005 0)
			(size 0 0)
			(layers "F.Cu" "F.Mask" "F.Paste")
			(net "P3V3_ADC_TIC")
		)
		(pad "2" smd circle
			(at 0.40005 0)
			(size 0 0)
			(layers "F.Cu" "F.Mask" "F.Paste")
			(net "GND")
		)
	)
	(footprint ""
		(layer "F.Cu")
		(at 374.802146 -341.716106 -90)
		(property "Reference" "PC1343"
			(at 0 0 270)
			(layer "F.SilkS")
			(hide yes)
			(effects
				(font
					(size 1.27 1.27)
				)
			)
		)
		(property "Value" ""
			(at 0 0 270)
			(layer "F.Fab")
			(effects
				(font
					(size 1.27 1.27)
				)
			)
		)
		(duplicate_pad_numbers_are_jumpers no)
		(fp_line
			(start -0.7874 0.4064)
			(end -0.7874 -0.4064)
			(stroke
				(width 0.1524)
				(type default)
			)
			(layer "F.SilkS")
		)
		(fp_line
			(start 0.7874 0.4064)
			(end -0.7874 0.4064)
			(stroke
				(width 0.1524)
				(type default)
			)
			(layer "F.SilkS")
		)
		(fp_line
			(start -0.7874 -0.4064)
			(end 0.7874 -0.4064)
			(stroke
				(width 0.1524)
				(type default)
			)
			(layer "F.SilkS")
		)
		(fp_line
			(start 0.7874 -0.4064)
			(end 0.7874 0.4064)
			(stroke
				(width 0.1524)
				(type default)
			)
			(layer "F.SilkS")
		)
		(fp_line
			(start -0.67945 0.3048)
			(end -0.67945 -0.305054)
			(stroke
				(width 0.1)
				(type default)
			)
			(layer "F.Fab")
		)
		(fp_line
			(start -0.12065 0.3048)
			(end -0.67945 0.3048)
			(stroke
				(width 0.1)
				(type default)
			)
			(layer "F.Fab")
		)
		(fp_line
			(start 0.120396 0.3048)
			(end 0.120396 0.2794)
			(stroke
				(width 0.1)
				(type default)
			)
			(layer "F.Fab")
		)
		(fp_line
			(start 0.67945 0.3048)
			(end 0.120396 0.3048)
			(stroke
				(width 0.1)
				(type default)
			)
			(layer "F.Fab")
		)
		(fp_line
			(start -0.12065 0.2794)
			(end -0.12065 0.3048)
			(stroke
				(width 0.1)
				(type default)
			)
			(layer "F.Fab")
		)
		(fp_line
			(start 0.120396 0.2794)
			(end -0.12065 0.2794)
			(stroke
				(width 0.1)
				(type default)
			)
			(layer "F.Fab")
		)
		(fp_line
			(start -0.12065 -0.2794)
			(end 0.12065 -0.2794)
			(stroke
				(width 0.1)
				(type default)
			)
			(layer "F.Fab")
		)
		(fp_line
			(start 0.12065 -0.2794)
			(end 0.12065 -0.3048)
			(stroke
				(width 0.1)
				(type default)
			)
			(layer "F.Fab")
		)
		(fp_line
			(start 0.12065 -0.3048)
			(end 0.67945 -0.3048)
			(stroke
				(width 0.1)
				(type default)
			)
			(layer "F.Fab")
		)
		(fp_line
			(start 0.67945 -0.3048)
			(end 0.67945 0.3048)
			(stroke
				(width 0.1)
				(type default)
			)
			(layer "F.Fab")
		)
		(fp_line
			(start -0.67945 -0.305054)
			(end -0.12065 -0.305054)
			(stroke
				(width 0.1)
				(type default)
			)
			(layer "F.Fab")
		)
		(fp_line
			(start -0.12065 -0.305054)
			(end -0.12065 -0.2794)
			(stroke
				(width 0.1)
				(type default)
			)
			(layer "F.Fab")
		)
		(pad "1" smd circle
			(at -0.40005 0 270)
			(size 0 0)
			(layers "F.Cu" "F.Mask" "F.Paste")
			(net "GND")
		)
		(pad "2" smd circle
			(at 0.40005 0 270)
			(size 0 0)
			(layers "F.Cu" "F.Mask" "F.Paste")
			(net "PVCCIN_CPU0_VREF")
		)
	)
	(footprint ""
		(layer "F.Cu")
		(at 140.7922 -104.116378 -90)
		(property "Reference" "R342"
			(at 0 0 270)
			(layer "F.SilkS")
			(hide yes)
			(effects
				(font
					(size 1.27 1.27)
				)
			)
		)
		(property "Value" ""
			(at 0 0 270)
			(layer "F.Fab")
			(effects
				(font
					(size 1.27 1.27)
				)
			)
		)
		(duplicate_pad_numbers_are_jumpers no)
		(fp_line
			(start -0.7874 0.4064)
			(end -0.7874 -0.4064)
			(stroke
				(width 0.1524)
				(type default)
			)
			(layer "F.SilkS")
		)
		(fp_line
			(start 0.7874 0.4064)
			(end -0.7874 0.4064)
			(stroke
				(width 0.1524)
				(type default)
			)
			(layer "F.SilkS")
		)
		(fp_line
			(start -0.7874 -0.4064)
			(end 0.7874 -0.4064)
			(stroke
				(width 0.1524)
				(type default)
			)
			(layer "F.SilkS")
		)
		(fp_line
			(start 0.7874 -0.4064)
			(end 0.7874 0.4064)
			(stroke
				(width 0.1524)
				(type default)
			)
			(layer "F.SilkS")
		)
		(fp_line
			(start -0.67945 0.3048)
			(end -0.67945 -0.305054)
			(stroke
				(width 0.1)
				(type default)
			)
			(layer "F.Fab")
		)
		(fp_line
			(start -0.12065 0.3048)
			(end -0.67945 0.3048)
			(stroke
				(width 0.1)
				(type default)
			)
			(layer "F.Fab")
		)
		(fp_line
			(start 0.120396 0.3048)
			(end 0.120396 0.2794)
			(stroke
				(width 0.1)
				(type default)
			)
			(layer "F.Fab")
		)
		(fp_line
			(start 0.67945 0.3048)
			(end 0.120396 0.3048)
			(stroke
				(width 0.1)
				(type default)
			)
			(layer "F.Fab")
		)
		(fp_line
			(start -0.12065 0.2794)
			(end -0.12065 0.3048)
			(stroke
				(width 0.1)
				(type default)
			)
			(layer "F.Fab")
		)
		(fp_line
			(start 0.120396 0.2794)
			(end -0.12065 0.2794)
			(stroke
				(width 0.1)
				(type default)
			)
			(layer "F.Fab")
		)
		(fp_line
			(start -0.12065 -0.2794)
			(end 0.12065 -0.2794)
			(stroke
				(width 0.1)
				(type default)
			)
			(layer "F.Fab")
		)
		(fp_line
			(start 0.12065 -0.2794)
			(end 0.12065 -0.3048)
			(stroke
				(width 0.1)
				(type default)
			)
			(layer "F.Fab")
		)
		(fp_line
			(start 0.12065 -0.3048)
			(end 0.67945 -0.3048)
			(stroke
				(width 0.1)
				(type default)
			)
			(layer "F.Fab")
		)
		(fp_line
			(start 0.67945 -0.3048)
			(end 0.67945 0.3048)
			(stroke
				(width 0.1)
				(type default)
			)
			(layer "F.Fab")
		)
		(fp_line
			(start -0.67945 -0.305054)
			(end -0.12065 -0.305054)
			(stroke
				(width 0.1)
				(type default)
			)
			(layer "F.Fab")
		)
		(fp_line
			(start -0.12065 -0.305054)
			(end -0.12065 -0.2794)
			(stroke
				(width 0.1)
				(type default)
			)
			(layer "F.Fab")
		)
		(pad "1" smd circle
			(at -0.40005 0 270)
			(size 0 0)
			(layers "F.Cu" "F.Mask" "F.Paste")
			(net "H_CPU_ERR1_LVC1_R_N")
		)
		(pad "2" smd circle
			(at 0.40005 0 270)
			(size 0 0)
			(layers "F.Cu" "F.Mask" "F.Paste")
			(net "H_CPU_ERR1_LVC1_N")
		)
	)
)
